# T6G (Grand Teton) — schematic netlist excerpt (pin names and nets, part order shuffled) for the footprints in the layout excerpt that follows; sources: Cadence DE-HDL packaged netlist, KiCad conversion of 04192023_DAF0TMB3IC0_F0TG_MB_C_brd_V02_OCP.brd

PC247  Q_CAP  1UF 6.3V 10% X7R  pkg 0402  page 210 : A = PVDD18_S5_P1 ; B = GND
PC1852  Q_CAP  0.1UF 25V 10% X7R  pkg 0402  page 189 : A = P5V_AUX ; B = GND
PC116_6  Q_CAP  22UF 16V 20% X6S  pkg C0805  page 203 : A = SW_P12V_AUX_PVDDCR_CPU1_P0_FLT ; B = GND

(kicad_pcb
	(version 20260206)
	(generator "pcbnew")
	(generator_version "10.0")
	(general
		(thickness 1.6)
		(legacy_teardrops no)
	)
	(paper "A4")
	(title_block
		(title "04192023_DAF0TMB3IC0_F0TG_MB_C_brd_V02_OCP.brd")
		(comment 1 "Grand Teton / footprints 6418-6420 of 8354")
	)
	(layers
		(0 "F.Cu" signal "TOP")
		(4 "In1.Cu" signal "GND")
		(6 "In2.Cu" signal "IN1")
		(8 "In3.Cu" signal "GND1")
		(10 "In4.Cu" signal "IN2")
		(12 "In5.Cu" signal "GND2")
		(14 "In6.Cu" signal "IN3")
		(16 "In7.Cu" signal "GND3")
		(18 "In8.Cu" signal "VCC")
		(20 "In9.Cu" signal "VCC1")
		(22 "In10.Cu" signal "GND4")
		(24 "In11.Cu" signal "IN4")
		(26 "In12.Cu" signal "GND5")
		(28 "In13.Cu" signal "IN5")
		(30 "In14.Cu" signal "GND6")
		(32 "In15.Cu" signal "IN6")
		(34 "In16.Cu" signal "GND7")
		(2 "B.Cu" signal "BOTTOM")
		(9 "F.Adhes" user "F.Adhesive")
		(11 "B.Adhes" user "B.Adhesive")
		(13 "F.Paste" user "Package Geometry/Pastemask Top")
		(15 "B.Paste" user "Package Geometry/Pastemask Bottom")
		(5 "F.SilkS" user "Ref Des/Silkscreen Top")
		(7 "B.SilkS" user "Ref Des/Silkscreen Bottom")
		(1 "F.Mask" user "Board Geometry/Soldermask Top")
		(3 "B.Mask" user "Board Geometry/Soldermask Bottom")
		(17 "Dwgs.User" user "User.Drawings")
		(19 "Cmts.User" user "User.Comments")
		(21 "Eco1.User" user "User.Eco1")
		(23 "Eco2.User" user "User.Eco2")
		(25 "Edge.Cuts" user "Board Geometry/Outline")
		(27 "Margin" user)
		(31 "F.CrtYd" user "Package Geometry/Place Bound Top")
		(29 "B.CrtYd" user "Package Geometry/Place Bound Bottom")
		(35 "F.Fab" user "Ref Des/Assembly Top")
		(33 "B.Fab" user "Ref Des/Assembly Bottom")
	)
	(footprint ""
		(layer "B.Cu")
		(at 90.209878 -144.88541)
		(property "Reference" "PC247"
			(at 0 0 0)
			(layer "B.SilkS")
			(hide yes)
			(effects
				(font
					(size 1.27 1.27)
				)
				(justify mirror)
			)
		)
		(property "Value" ""
			(at 0 0 0)
			(layer "B.Fab")
			(effects
				(font
					(size 1.27 1.27)
				)
				(justify mirror)
			)
		)
		(duplicate_pad_numbers_are_jumpers no)
		(fp_line
			(start -0.7874 -0.4064)
			(end -0.7874 0.4064)
			(stroke
				(width 0.1524)
				(type default)
			)
			(layer "B.SilkS")
		)
		(fp_line
			(start -0.7874 0.4064)
			(end 0.7874 0.4064)
			(stroke
				(width 0.1524)
				(type default)
			)
			(layer "B.SilkS")
		)
		(fp_line
			(start 0.7874 -0.4064)
			(end -0.7874 -0.4064)
			(stroke
				(width 0.1524)
				(type default)
			)
			(layer "B.SilkS")
		)
		(fp_line
			(start 0.7874 0.4064)
			(end 0.7874 -0.4064)
			(stroke
				(width 0.1524)
				(type default)
			)
			(layer "B.SilkS")
		)
		(fp_line
			(start -0.67945 -0.3048)
			(end -0.67945 0.3048)
			(stroke
				(width 0.1)
				(type default)
			)
			(layer "B.Fab")
		)
		(fp_line
			(start -0.67945 0.3048)
			(end -0.120396 0.3048)
			(stroke
				(width 0.1)
				(type default)
			)
			(layer "B.Fab")
		)
		(fp_line
			(start -0.12065 -0.3048)
			(end -0.67945 -0.3048)
			(stroke
				(width 0.1)
				(type default)
			)
			(layer "B.Fab")
		)
		(fp_line
			(start -0.12065 -0.2794)
			(end -0.12065 -0.3048)
			(stroke
				(width 0.1)
				(type default)
			)
			(layer "B.Fab")
		)
		(fp_line
			(start -0.120396 0.2794)
			(end 0.12065 0.2794)
			(stroke
				(width 0.1)
				(type default)
			)
			(layer "B.Fab")
		)
		(fp_line
			(start -0.120396 0.3048)
			(end -0.120396 0.2794)
			(stroke
				(width 0.1)
				(type default)
			)
			(layer "B.Fab")
		)
		(fp_line
			(start 0.12065 -0.305054)
			(end 0.12065 -0.2794)
			(stroke
				(width 0.1)
				(type default)
			)
			(layer "B.Fab")
		)
		(fp_line
			(start 0.12065 -0.2794)
			(end -0.12065 -0.2794)
			(stroke
				(width 0.1)
				(type default)
			)
			(layer "B.Fab")
		)
		(fp_line
			(start 0.12065 0.2794)
			(end 0.12065 0.3048)
			(stroke
				(width 0.1)
				(type default)
			)
			(layer "B.Fab")
		)
		(fp_line
			(start 0.12065 0.3048)
			(end 0.67945 0.3048)
			(stroke
				(width 0.1)
				(type default)
			)
			(layer "B.Fab")
		)
		(fp_line
			(start 0.67945 -0.305054)
			(end 0.12065 -0.305054)
			(stroke
				(width 0.1)
				(type default)
			)
			(layer "B.Fab")
		)
		(fp_line
			(start 0.67945 0.3048)
			(end 0.67945 -0.305054)
			(stroke
				(width 0.1)
				(type default)
			)
			(layer "B.Fab")
		)
		(pad "1" smd circle
			(at 0.40005 0 180)
			(size 0 0)
			(layers "B.Cu" "B.Mask" "B.Paste")
			(net "PVDD18_S5_P1")
		)
		(pad "2" smd circle
			(at -0.40005 0 180)
			(size 0 0)
			(layers "B.Cu" "B.Mask" "B.Paste")
			(net "GND")
		)
	)
	(footprint ""
		(layer "B.Cu")
		(at 408.721814 -151.614124 90)
		(property "Reference" "PC1852"
			(at 0 0 90)
			(layer "B.SilkS")
			(hide yes)
			(effects
				(font
					(size 1.27 1.27)
				)
				(justify mirror)
			)
		)
		(property "Value" ""
			(at 0 0 90)
			(layer "B.Fab")
			(effects
				(font
					(size 1.27 1.27)
				)
				(justify mirror)
			)
		)
		(duplicate_pad_numbers_are_jumpers no)
		(fp_line
			(start 0.7874 -0.4064)
			(end -0.7874 -0.4064)
			(stroke
				(width 0.1524)
				(type default)
			)
			(layer "B.SilkS")
		)
		(fp_line
			(start -0.7874 -0.4064)
			(end -0.7874 0.4064)
			(stroke
				(width 0.1524)
				(type default)
			)
			(layer "B.SilkS")
		)
		(fp_line
			(start 0.7874 0.4064)
			(end 0.7874 -0.4064)
			(stroke
				(width 0.1524)
				(type default)
			)
			(layer "B.SilkS")
		)
		(fp_line
			(start -0.7874 0.4064)
			(end 0.7874 0.4064)
			(stroke
				(width 0.1524)
				(type default)
			)
			(layer "B.SilkS")
		)
		(fp_line
			(start 0.67945 -0.305054)
			(end 0.12065 -0.305054)
			(stroke
				(width 0.1)
				(type default)
			)
			(layer "B.Fab")
		)
		(fp_line
			(start 0.12065 -0.305054)
			(end 0.12065 -0.2794)
			(stroke
				(width 0.1)
				(type default)
			)
			(layer "B.Fab")
		)
		(fp_line
			(start -0.12065 -0.3048)
			(end -0.67945 -0.3048)
			(stroke
				(width 0.1)
				(type default)
			)
			(layer "B.Fab")
		)
		(fp_line
			(start -0.67945 -0.3048)
			(end -0.67945 0.3048)
			(stroke
				(width 0.1)
				(type default)
			)
			(layer "B.Fab")
		)
		(fp_line
			(start 0.12065 -0.2794)
			(end -0.12065 -0.2794)
			(stroke
				(width 0.1)
				(type default)
			)
			(layer "B.Fab")
		)
		(fp_line
			(start -0.12065 -0.2794)
			(end -0.12065 -0.3048)
			(stroke
				(width 0.1)
				(type default)
			)
			(layer "B.Fab")
		)
		(fp_line
			(start 0.12065 0.2794)
			(end 0.12065 0.3048)
			(stroke
				(width 0.1)
				(type default)
			)
			(layer "B.Fab")
		)
		(fp_line
			(start -0.120396 0.2794)
			(end 0.12065 0.2794)
			(stroke
				(width 0.1)
				(type default)
			)
			(layer "B.Fab")
		)
		(fp_line
			(start 0.67945 0.3048)
			(end 0.67945 -0.305054)
			(stroke
				(width 0.1)
				(type default)
			)
			(layer "B.Fab")
		)
		(fp_line
			(start 0.12065 0.3048)
			(end 0.67945 0.3048)
			(stroke
				(width 0.1)
				(type default)
			)
			(layer "B.Fab")
		)
		(fp_line
			(start -0.120396 0.3048)
			(end -0.120396 0.2794)
			(stroke
				(width 0.1)
				(type default)
			)
			(layer "B.Fab")
		)
		(fp_line
			(start -0.67945 0.3048)
			(end -0.120396 0.3048)
			(stroke
				(width 0.1)
				(type default)
			)
			(layer "B.Fab")
		)
		(pad "1" smd circle
			(at 0.40005 0 270)
			(size 0 0)
			(layers "B.Cu" "B.Mask" "B.Paste")
			(net "P5V_AUX")
		)
		(pad "2" smd circle
			(at -0.40005 0 270)
			(size 0 0)
			(layers "B.Cu" "B.Mask" "B.Paste")
			(net "GND")
		)
	)
	(footprint ""
		(layer "B.Cu")
		(at 352.787712 -343.87409 -90)
		(property "Reference" "PC116_6"
			(at 0 0 90)
			(layer "B.SilkS")
			(hide yes)
			(effects
				(font
					(size 1.27 1.27)
				)
				(justify mirror)
			)
		)
		(property "Value" ""
			(at 0 0 90)
			(layer "B.Fab")
			(effects
				(font
					(size 1.27 1.27)
				)
				(justify mirror)
			)
		)
		(duplicate_pad_numbers_are_jumpers no)
		(fp_line
			(start -1.524 0.762)
			(end 1.524 0.762)
			(stroke
				(width 0.1524)
				(type default)
			)
			(layer "B.SilkS")
		)
		(fp_line
			(start 1.524 0.762)
			(end 1.524 -0.762)
			(stroke
				(width 0.1524)
				(type default)
			)
			(layer "B.SilkS")
		)
		(fp_line
			(start -1.524 -0.762)
			(end -1.524 0.762)
			(stroke
				(width 0.1524)
				(type default)
			)
			(layer "B.SilkS")
		)
		(fp_line
			(start 1.524 -0.762)
			(end -1.524 -0.762)
			(stroke
				(width 0.1524)
				(type default)
			)
			(layer "B.SilkS")
		)
		(fp_line
			(start -1.1049 0.724916)
			(end -1.1049 -0.724916)
			(stroke
				(width 0.1)
				(type default)
			)
			(layer "B.Fab")
		)
		(fp_line
			(start 1.1049 0.724916)
			(end -1.1049 0.724916)
			(stroke
				(width 0.1)
				(type default)
			)
			(layer "B.Fab")
		)
		(fp_line
			(start -1.1049 -0.724916)
			(end 1.1049 -0.724916)
			(stroke
				(width 0.1)
				(type default)
			)
			(layer "B.Fab")
		)
		(fp_line
			(start 1.1049 -0.724916)
			(end 1.1049 0.724916)
			(stroke
				(width 0.1)
				(type default)
			)
			(layer "B.Fab")
		)
		(pad "1" smd rect
			(at 0.889 0 270)
			(size 1.016 1.27)
			(layers "B.Cu" "B.Mask" "B.Paste")
			(net "SW_P12V_AUX_PVDDCR_CPU1_P0_FLT")
		)
		(pad "2" smd rect
			(at -0.889 0 270)
			(size 1.016 1.27)
			(layers "B.Cu" "B.Mask" "B.Paste")
			(net "GND")
		)
	)
)
